# Bryce Canyon_Storage_Controller_Card_Stackup.xlsx — PCB Test Plan_HVM(90+) (pcb-stackup)
|  | Board vendor give feedback of quantity in yellow columns based on the AQL table or description. |  |  |  |  |  |  |  |  |  |  |  |  |  |  |
|  | Wiwynn PM give feedback in blue columns |  |  |  |  |  |  |  |  |  |  |  |  |  |  |
| Person to be informed : PCB vendor, EE, SI, PM, PSM, Buyer, SQM |  |  |  |  |  |  |  |  |  |  |  |  |  |  |  |
| Simple flow : SI (test requirements) -> PM/AM (Total PCBS demand) -> Buyer -> Board Vendor (yellow column feedback) -> Buyer -> Person to be informed (Check and Track) |  |  |  |  |  |  |  |  |  |  |  |  |  |  |  |
| PO(purchase order) : If there are many POs for this PCB, 1st sample quantity is based on 1st PO, 2nd sample quantity is based on 2nd PO. |  |  |  |  |  |  |  |  |  |  |  |  |  |  |  |
| Project Name | PCB name | PCB# (1XXXX-XX) | Product Stage | Batch# | PCB Vendor | Production  Lot size | PCBs Demand | Delta-L Coupon (PCB Vendor) | Delta-L Coupon (3rd Party Lab) | Impedance Coupon (PCB Vendor) | In-board trace correlation (PCB Vendor) | X-section Analysis (PCB Vendor) | IST (3rd Party Lab) | IPC-6012D (3rd Party Lab) | Note |
| Bryce Canyon | SCC | 16316-1 | HVM(90+ days) | N/A |  |  | TBD | No | No | Yes | No | No | No | No | Need Test? (Yes, No) |
| Tracking Code On Both Of Coupon And PCB |  |  |  |  |  |  |  |  |  | N/A |  |  |  |  |  |
| Test Item Acceptance Criteria |  |  |  |  |  |  |  |  |  | c = 0 |  |  |  |  |  |
| Test Item Sampling Quantity |  |  |  |  |  |  |  |  |  | Mil-STD 105E single sampling plan, AQL 0.65, level 2 |  |  |  |  |  |
| Test Time (working days) |  |  |  |  |  |  |  |  |  |  |  |  |  |  |  |
| Test Item Shipping Quantity |  |  |  |  |  |  |  |  |  |  |  |  |  |  |  |
| Shipping Address |  |  |  |  |  |  |  |  |  |  |  |  |  |  |  |
| Receiver Name |  |  |  |  |  |  |  |  |  |  |  |  |  |  |  |
| Receiver Phone# |  |  |  |  |  |  |  |  |  |  |  |  |  |  |  |
